(kicad_pcb
	(version 20260206)
	(generator "pcbnew")
	(generator_version "10.0")
	(general
		(thickness 1.6)
		(legacy_teardrops no)
	)
	(paper "A4")
	(title_block
		(title "03242023_DA0F0TMBIJ0_F0T_Motherboard_J_brd_V01_OCP.brd")
		(comment 1 "Grand Teton / footprints 5782-5788 of 6105")
	)
	(layers
		(0 "F.Cu" signal "TOP")
		(4 "In1.Cu" signal "GND")
		(6 "In2.Cu" signal "IN1")
		(8 "In3.Cu" signal "GND1")
		(10 "In4.Cu" signal "IN2")
		(12 "In5.Cu" signal "GND2")
		(14 "In6.Cu" signal "IN3")
		(16 "In7.Cu" signal "GND3")
		(18 "In8.Cu" signal "VCC")
		(20 "In9.Cu" signal "VCC1")
		(22 "In10.Cu" signal "GND4")
		(24 "In11.Cu" signal "IN4")
		(26 "In12.Cu" signal "GND5")
		(28 "In13.Cu" signal "IN5")
		(30 "In14.Cu" signal "GND6")
		(32 "In15.Cu" signal "IN6")
		(34 "In16.Cu" signal "GND7")
		(2 "B.Cu" signal "BOTTOM")
		(9 "F.Adhes" user "F.Adhesive")
		(11 "B.Adhes" user "B.Adhesive")
		(13 "F.Paste" user "Package Geometry/Pastemask Top")
		(15 "B.Paste" user "Package Geometry/Pastemask Bottom")
		(5 "F.SilkS" user "Ref Des/Silkscreen Top")
		(7 "B.SilkS" user "Ref Des/Silkscreen Bottom")
		(1 "F.Mask" user "Board Geometry/Soldermask Top")
		(3 "B.Mask" user "Board Geometry/Soldermask Bottom")
		(17 "Dwgs.User" user "User.Drawings")
		(19 "Cmts.User" user "User.Comments")
		(21 "Eco1.User" user "User.Eco1")
		(23 "Eco2.User" user "User.Eco2")
		(25 "Edge.Cuts" user "Board Geometry/Outline")
		(27 "Margin" user)
		(31 "F.CrtYd" user "Package Geometry/Place Bound Top")
		(29 "B.CrtYd" user "Package Geometry/Place Bound Bottom")
		(35 "F.Fab" user "Ref Des/Assembly Top")
		(33 "B.Fab" user "Ref Des/Assembly Bottom")
	)
	(footprint ""
		(layer "B.Cu")
		(at 157.02788 -115.026948 180)
		(property "Reference" "R3478"
			(at 0 0 0)
			(layer "B.SilkS")
			(hide yes)
			(effects
				(font
					(size 1.27 1.27)
				)
				(justify mirror)
			)
		)
		(property "Value" ""
			(at 0 0 0)
			(layer "B.Fab")
			(effects
				(font
					(size 1.27 1.27)
				)
				(justify mirror)
			)
		)
		(duplicate_pad_numbers_are_jumpers no)
		(fp_line
			(start 0.7874 0.4064)
			(end 0.7874 -0.4064)
			(stroke
				(width 0.1524)
				(type default)
			)
			(layer "B.SilkS")
		)
		(fp_line
			(start 0.7874 -0.4064)
			(end -0.7874 -0.4064)
			(stroke
				(width 0.1524)
				(type default)
			)
			(layer "B.SilkS")
		)
		(fp_line
			(start -0.7874 0.4064)
			(end 0.7874 0.4064)
			(stroke
				(width 0.1524)
				(type default)
			)
			(layer "B.SilkS")
		)
		(fp_line
			(start -0.7874 -0.4064)
			(end -0.7874 0.4064)
			(stroke
				(width 0.1524)
				(type default)
			)
			(layer "B.SilkS")
		)
		(fp_line
			(start 0.67945 0.3048)
			(end 0.67945 -0.305054)
			(stroke
				(width 0.1)
				(type default)
			)
			(layer "B.Fab")
		)
		(fp_line
			(start 0.67945 -0.305054)
			(end 0.12065 -0.305054)
			(stroke
				(width 0.1)
				(type default)
			)
			(layer "B.Fab")
		)
		(fp_line
			(start 0.12065 0.3048)
			(end 0.67945 0.3048)
			(stroke
				(width 0.1)
				(type default)
			)
			(layer "B.Fab")
		)
		(fp_line
			(start 0.12065 0.2794)
			(end 0.12065 0.3048)
			(stroke
				(width 0.1)
				(type default)
			)
			(layer "B.Fab")
		)
		(fp_line
			(start 0.12065 -0.2794)
			(end -0.12065 -0.2794)
			(stroke
				(width 0.1)
				(type default)
			)
			(layer "B.Fab")
		)
		(fp_line
			(start 0.12065 -0.305054)
			(end 0.12065 -0.2794)
			(stroke
				(width 0.1)
				(type default)
			)
			(layer "B.Fab")
		)
		(fp_line
			(start -0.120396 0.3048)
			(end -0.120396 0.2794)
			(stroke
				(width 0.1)
				(type default)
			)
			(layer "B.Fab")
		)
		(fp_line
			(start -0.120396 0.2794)
			(end 0.12065 0.2794)
			(stroke
				(width 0.1)
				(type default)
			)
			(layer "B.Fab")
		)
		(fp_line
			(start -0.12065 -0.2794)
			(end -0.12065 -0.3048)
			(stroke
				(width 0.1)
				(type default)
			)
			(layer "B.Fab")
		)
		(fp_line
			(start -0.12065 -0.3048)
			(end -0.67945 -0.3048)
			(stroke
				(width 0.1)
				(type default)
			)
			(layer "B.Fab")
		)
		(fp_line
			(start -0.67945 0.3048)
			(end -0.120396 0.3048)
			(stroke
				(width 0.1)
				(type default)
			)
			(layer "B.Fab")
		)
		(fp_line
			(start -0.67945 -0.3048)
			(end -0.67945 0.3048)
			(stroke
				(width 0.1)
				(type default)
			)
			(layer "B.Fab")
		)
		(pad "1" smd circle
			(at 0.40005 0)
			(size 0 0)
			(layers "B.Cu" "B.Mask" "B.Paste")
			(net "GPU_FPGA_EROT_RST_N")
		)
		(pad "2" smd circle
			(at -0.40005 0)
			(size 0 0)
			(layers "B.Cu" "B.Mask" "B.Paste")
			(net "GPU_FPGA_EROT_RST_R_N")
		)
	)
	(footprint ""
		(layer "B.Cu")
		(at 320.170556 -56.612028 90)
		(property "Reference" "R1260"
			(at 0 0 90)
			(layer "B.SilkS")
			(hide yes)
			(effects
				(font
					(size 1.27 1.27)
				)
				(justify mirror)
			)
		)
		(property "Value" ""
			(at 0 0 90)
			(layer "B.Fab")
			(effects
				(font
					(size 1.27 1.27)
				)
				(justify mirror)
			)
		)
		(duplicate_pad_numbers_are_jumpers no)
		(fp_line
			(start 0.7874 -0.4064)
			(end -0.7874 -0.4064)
			(stroke
				(width 0.1524)
				(type default)
			)
			(layer "B.SilkS")
		)
		(fp_line
			(start -0.7874 -0.4064)
			(end -0.7874 0.4064)
			(stroke
				(width 0.1524)
				(type default)
			)
			(layer "B.SilkS")
		)
		(fp_line
			(start 0.7874 0.4064)
			(end 0.7874 -0.4064)
			(stroke
				(width 0.1524)
				(type default)
			)
			(layer "B.SilkS")
		)
		(fp_line
			(start -0.7874 0.4064)
			(end 0.7874 0.4064)
			(stroke
				(width 0.1524)
				(type default)
			)
			(layer "B.SilkS")
		)
		(fp_line
			(start 0.67945 -0.305054)
			(end 0.12065 -0.305054)
			(stroke
				(width 0.1)
				(type default)
			)
			(layer "B.Fab")
		)
		(fp_line
			(start 0.12065 -0.305054)
			(end 0.12065 -0.2794)
			(stroke
				(width 0.1)
				(type default)
			)
			(layer "B.Fab")
		)
		(fp_line
			(start -0.12065 -0.3048)
			(end -0.67945 -0.3048)
			(stroke
				(width 0.1)
				(type default)
			)
			(layer "B.Fab")
		)
		(fp_line
			(start -0.67945 -0.3048)
			(end -0.67945 0.3048)
			(stroke
				(width 0.1)
				(type default)
			)
			(layer "B.Fab")
		)
		(fp_line
			(start 0.12065 -0.2794)
			(end -0.12065 -0.2794)
			(stroke
				(width 0.1)
				(type default)
			)
			(layer "B.Fab")
		)
		(fp_line
			(start -0.12065 -0.2794)
			(end -0.12065 -0.3048)
			(stroke
				(width 0.1)
				(type default)
			)
			(layer "B.Fab")
		)
		(fp_line
			(start 0.12065 0.2794)
			(end 0.12065 0.3048)
			(stroke
				(width 0.1)
				(type default)
			)
			(layer "B.Fab")
		)
		(fp_line
			(start -0.120396 0.2794)
			(end 0.12065 0.2794)
			(stroke
				(width 0.1)
				(type default)
			)
			(layer "B.Fab")
		)
		(fp_line
			(start 0.67945 0.3048)
			(end 0.67945 -0.305054)
			(stroke
				(width 0.1)
				(type default)
			)
			(layer "B.Fab")
		)
		(fp_line
			(start 0.12065 0.3048)
			(end 0.67945 0.3048)
			(stroke
				(width 0.1)
				(type default)
			)
			(layer "B.Fab")
		)
		(fp_line
			(start -0.120396 0.3048)
			(end -0.120396 0.2794)
			(stroke
				(width 0.1)
				(type default)
			)
			(layer "B.Fab")
		)
		(fp_line
			(start -0.67945 0.3048)
			(end -0.120396 0.3048)
			(stroke
				(width 0.1)
				(type default)
			)
			(layer "B.Fab")
		)
		(pad "1" smd circle
			(at 0.40005 0 270)
			(size 0 0)
			(layers "B.Cu" "B.Mask" "B.Paste")
			(net "P1V05_PCH_AUX")
		)
		(pad "2" smd circle
			(at -0.40005 0 270)
			(size 0 0)
			(layers "B.Cu" "B.Mask" "B.Paste")
			(net "H_CPU_ERR0_PCH_R_N")
		)
	)
	(footprint ""
		(layer "B.Cu")
		(at 179.454048 -405.288242 180)
		(property "Reference" "PR2106"
			(at 0 0 0)
			(layer "B.SilkS")
			(hide yes)
			(effects
				(font
					(size 1.27 1.27)
				)
				(justify mirror)
			)
		)
		(property "Value" ""
			(at 0 0 0)
			(layer "B.Fab")
			(effects
				(font
					(size 1.27 1.27)
				)
				(justify mirror)
			)
		)
		(duplicate_pad_numbers_are_jumpers no)
		(fp_line
			(start 0.7874 0.4064)
			(end 0.7874 -0.4064)
			(stroke
				(width 0.1524)
				(type default)
			)
			(layer "B.SilkS")
		)
		(fp_line
			(start 0.7874 -0.4064)
			(end -0.7874 -0.4064)
			(stroke
				(width 0.1524)
				(type default)
			)
			(layer "B.SilkS")
		)
		(fp_line
			(start -0.7874 0.4064)
			(end 0.7874 0.4064)
			(stroke
				(width 0.1524)
				(type default)
			)
			(layer "B.SilkS")
		)
		(fp_line
			(start -0.7874 -0.4064)
			(end -0.7874 0.4064)
			(stroke
				(width 0.1524)
				(type default)
			)
			(layer "B.SilkS")
		)
		(fp_line
			(start 0.67945 0.3048)
			(end 0.67945 -0.305054)
			(stroke
				(width 0.1)
				(type default)
			)
			(layer "B.Fab")
		)
		(fp_line
			(start 0.67945 -0.305054)
			(end 0.12065 -0.305054)
			(stroke
				(width 0.1)
				(type default)
			)
			(layer "B.Fab")
		)
		(fp_line
			(start 0.12065 0.3048)
			(end 0.67945 0.3048)
			(stroke
				(width 0.1)
				(type default)
			)
			(layer "B.Fab")
		)
		(fp_line
			(start 0.12065 0.2794)
			(end 0.12065 0.3048)
			(stroke
				(width 0.1)
				(type default)
			)
			(layer "B.Fab")
		)
		(fp_line
			(start 0.12065 -0.2794)
			(end -0.12065 -0.2794)
			(stroke
				(width 0.1)
				(type default)
			)
			(layer "B.Fab")
		)
		(fp_line
			(start 0.12065 -0.305054)
			(end 0.12065 -0.2794)
			(stroke
				(width 0.1)
				(type default)
			)
			(layer "B.Fab")
		)
		(fp_line
			(start -0.120396 0.3048)
			(end -0.120396 0.2794)
			(stroke
				(width 0.1)
				(type default)
			)
			(layer "B.Fab")
		)
		(fp_line
			(start -0.120396 0.2794)
			(end 0.12065 0.2794)
			(stroke
				(width 0.1)
				(type default)
			)
			(layer "B.Fab")
		)
		(fp_line
			(start -0.12065 -0.2794)
			(end -0.12065 -0.3048)
			(stroke
				(width 0.1)
				(type default)
			)
			(layer "B.Fab")
		)
		(fp_line
			(start -0.12065 -0.3048)
			(end -0.67945 -0.3048)
			(stroke
				(width 0.1)
				(type default)
			)
			(layer "B.Fab")
		)
		(fp_line
			(start -0.67945 0.3048)
			(end -0.120396 0.3048)
			(stroke
				(width 0.1)
				(type default)
			)
			(layer "B.Fab")
		)
		(fp_line
			(start -0.67945 -0.3048)
			(end -0.67945 0.3048)
			(stroke
				(width 0.1)
				(type default)
			)
			(layer "B.Fab")
		)
		(pad "1" smd circle
			(at 0.40005 0)
			(size 0 0)
			(layers "B.Cu" "B.Mask" "B.Paste")
			(net "HSC_VDD")
		)
		(pad "2" smd circle
			(at -0.40005 0)
			(size 0 0)
			(layers "B.Cu" "B.Mask" "B.Paste")
			(net "HSC_VIN_UVW_N")
		)
	)
	(footprint ""
		(layer "B.Cu")
		(at 47.689516 -319.009522)
		(property "Reference" "R45"
			(at 0 0 0)
			(layer "B.SilkS")
			(hide yes)
			(effects
				(font
					(size 1.27 1.27)
				)
				(justify mirror)
			)
		)
		(property "Value" ""
			(at 0 0 0)
			(layer "B.Fab")
			(effects
				(font
					(size 1.27 1.27)
				)
				(justify mirror)
			)
		)
		(duplicate_pad_numbers_are_jumpers no)
		(fp_line
			(start -0.7874 -0.4064)
			(end -0.7874 0.4064)
			(stroke
				(width 0.1524)
				(type default)
			)
			(layer "B.SilkS")
		)
		(fp_line
			(start -0.7874 0.4064)
			(end 0.7874 0.4064)
			(stroke
				(width 0.1524)
				(type default)
			)
			(layer "B.SilkS")
		)
		(fp_line
			(start 0.7874 -0.4064)
			(end -0.7874 -0.4064)
			(stroke
				(width 0.1524)
				(type default)
			)
			(layer "B.SilkS")
		)
		(fp_line
			(start 0.7874 0.4064)
			(end 0.7874 -0.4064)
			(stroke
				(width 0.1524)
				(type default)
			)
			(layer "B.SilkS")
		)
		(fp_line
			(start -0.67945 -0.3048)
			(end -0.67945 0.3048)
			(stroke
				(width 0.1)
				(type default)
			)
			(layer "B.Fab")
		)
		(fp_line
			(start -0.67945 0.3048)
			(end -0.120396 0.3048)
			(stroke
				(width 0.1)
				(type default)
			)
			(layer "B.Fab")
		)
		(fp_line
			(start -0.12065 -0.3048)
			(end -0.67945 -0.3048)
			(stroke
				(width 0.1)
				(type default)
			)
			(layer "B.Fab")
		)
		(fp_line
			(start -0.12065 -0.2794)
			(end -0.12065 -0.3048)
			(stroke
				(width 0.1)
				(type default)
			)
			(layer "B.Fab")
		)
		(fp_line
			(start -0.120396 0.2794)
			(end 0.12065 0.2794)
			(stroke
				(width 0.1)
				(type default)
			)
			(layer "B.Fab")
		)
		(fp_line
			(start -0.120396 0.3048)
			(end -0.120396 0.2794)
			(stroke
				(width 0.1)
				(type default)
			)
			(layer "B.Fab")
		)
		(fp_line
			(start 0.12065 -0.305054)
			(end 0.12065 -0.2794)
			(stroke
				(width 0.1)
				(type default)
			)
			(layer "B.Fab")
		)
		(fp_line
			(start 0.12065 -0.2794)
			(end -0.12065 -0.2794)
			(stroke
				(width 0.1)
				(type default)
			)
			(layer "B.Fab")
		)
		(fp_line
			(start 0.12065 0.2794)
			(end 0.12065 0.3048)
			(stroke
				(width 0.1)
				(type default)
			)
			(layer "B.Fab")
		)
		(fp_line
			(start 0.12065 0.3048)
			(end 0.67945 0.3048)
			(stroke
				(width 0.1)
				(type default)
			)
			(layer "B.Fab")
		)
		(fp_line
			(start 0.67945 -0.305054)
			(end 0.12065 -0.305054)
			(stroke
				(width 0.1)
				(type default)
			)
			(layer "B.Fab")
		)
		(fp_line
			(start 0.67945 0.3048)
			(end 0.67945 -0.305054)
			(stroke
				(width 0.1)
				(type default)
			)
			(layer "B.Fab")
		)
		(pad "1" smd circle
			(at 0.40005 0 180)
			(size 0 0)
			(layers "B.Cu" "B.Mask" "B.Paste")
			(net "PD_CHB_CPU1_DIMM2_SAA")
		)
		(pad "2" smd circle
			(at -0.40005 0 180)
			(size 0 0)
			(layers "B.Cu" "B.Mask" "B.Paste")
			(net "GND")
		)
	)
	(footprint ""
		(layer "B.Cu")
		(at 123.57862 -28.265628)
		(property "Reference" "C2291"
			(at 0 0 0)
			(layer "B.SilkS")
			(hide yes)
			(effects
				(font
					(size 1.27 1.27)
				)
				(justify mirror)
			)
		)
		(property "Value" ""
			(at 0 0 0)
			(layer "B.Fab")
			(effects
				(font
					(size 1.27 1.27)
				)
				(justify mirror)
			)
		)
		(duplicate_pad_numbers_are_jumpers no)
		(fp_line
			(start -0.299974 -0.150114)
			(end -0.299974 0.150114)
			(stroke
				(width 0.1)
				(type default)
			)
			(layer "B.Fab")
		)
		(fp_line
			(start -0.299974 0.150114)
			(end 0.299974 0.150114)
			(stroke
				(width 0.1)
				(type default)
			)
			(layer "B.Fab")
		)
		(fp_line
			(start 0.299974 -0.150114)
			(end -0.299974 -0.150114)
			(stroke
				(width 0.1)
				(type default)
			)
			(layer "B.Fab")
		)
		(fp_line
			(start 0.299974 0.150114)
			(end 0.299974 -0.150114)
			(stroke
				(width 0.1)
				(type default)
			)
			(layer "B.Fab")
		)
		(pad "1" smd rect
			(at 0.2667 0 180)
			(size 0.3048 0.381)
			(layers "B.Cu" "B.Mask" "B.Paste")
			(net "USB3_PCH_RX_BUF_C_DP<4>")
		)
		(pad "2" smd rect
			(at -0.2667 0 180)
			(size 0.3048 0.381)
			(layers "B.Cu" "B.Mask" "B.Paste")
			(net "USB3_PCH_RX_BUF_DP<4>")
		)
	)
	(footprint ""
		(layer "B.Cu")
		(at 385.1402 -79.428848)
		(property "Reference" "PR1850"
			(at 0 0 0)
			(layer "B.SilkS")
			(hide yes)
			(effects
				(font
					(size 1.27 1.27)
				)
				(justify mirror)
			)
		)
		(property "Value" ""
			(at 0 0 0)
			(layer "B.Fab")
			(effects
				(font
					(size 1.27 1.27)
				)
				(justify mirror)
			)
		)
		(duplicate_pad_numbers_are_jumpers no)
		(fp_line
			(start -0.7874 -0.4064)
			(end -0.7874 0.4064)
			(stroke
				(width 0.1524)
				(type default)
			)
			(layer "B.SilkS")
		)
		(fp_line
			(start -0.7874 0.4064)
			(end 0.7874 0.4064)
			(stroke
				(width 0.1524)
				(type default)
			)
			(layer "B.SilkS")
		)
		(fp_line
			(start 0.7874 -0.4064)
			(end -0.7874 -0.4064)
			(stroke
				(width 0.1524)
				(type default)
			)
			(layer "B.SilkS")
		)
		(fp_line
			(start 0.7874 0.4064)
			(end 0.7874 -0.4064)
			(stroke
				(width 0.1524)
				(type default)
			)
			(layer "B.SilkS")
		)
		(fp_line
			(start -0.67945 -0.3048)
			(end -0.67945 0.3048)
			(stroke
				(width 0.1)
				(type default)
			)
			(layer "B.Fab")
		)
		(fp_line
			(start -0.67945 0.3048)
			(end -0.120396 0.3048)
			(stroke
				(width 0.1)
				(type default)
			)
			(layer "B.Fab")
		)
		(fp_line
			(start -0.12065 -0.3048)
			(end -0.67945 -0.3048)
			(stroke
				(width 0.1)
				(type default)
			)
			(layer "B.Fab")
		)
		(fp_line
			(start -0.12065 -0.2794)
			(end -0.12065 -0.3048)
			(stroke
				(width 0.1)
				(type default)
			)
			(layer "B.Fab")
		)
		(fp_line
			(start -0.120396 0.2794)
			(end 0.12065 0.2794)
			(stroke
				(width 0.1)
				(type default)
			)
			(layer "B.Fab")
		)
		(fp_line
			(start -0.120396 0.3048)
			(end -0.120396 0.2794)
			(stroke
				(width 0.1)
				(type default)
			)
			(layer "B.Fab")
		)
		(fp_line
			(start 0.12065 -0.305054)
			(end 0.12065 -0.2794)
			(stroke
				(width 0.1)
				(type default)
			)
			(layer "B.Fab")
		)
		(fp_line
			(start 0.12065 -0.2794)
			(end -0.12065 -0.2794)
			(stroke
				(width 0.1)
				(type default)
			)
			(layer "B.Fab")
		)
		(fp_line
			(start 0.12065 0.2794)
			(end 0.12065 0.3048)
			(stroke
				(width 0.1)
				(type default)
			)
			(layer "B.Fab")
		)
		(fp_line
			(start 0.12065 0.3048)
			(end 0.67945 0.3048)
			(stroke
				(width 0.1)
				(type default)
			)
			(layer "B.Fab")
		)
		(fp_line
			(start 0.67945 -0.305054)
			(end 0.12065 -0.305054)
			(stroke
				(width 0.1)
				(type default)
			)
			(layer "B.Fab")
		)
		(fp_line
			(start 0.67945 0.3048)
			(end 0.67945 -0.305054)
			(stroke
				(width 0.1)
				(type default)
			)
			(layer "B.Fab")
		)
		(pad "1" smd circle
			(at 0.40005 0 180)
			(size 0 0)
			(layers "B.Cu" "B.Mask" "B.Paste")
			(net "GND")
		)
		(pad "2" smd circle
			(at -0.40005 0 180)
			(size 0 0)
			(layers "B.Cu" "B.Mask" "B.Paste")
			(net "FM_PCH_P1V8_AUX_EN_R")
		)
	)
	(footprint ""
		(layer "B.Cu")
		(at 216.212674 -76.591668 180)
		(property "Reference" "R3211"
			(at 0 0 0)
			(layer "B.SilkS")
			(hide yes)
			(effects
				(font
					(size 1.27 1.27)
				)
				(justify mirror)
			)
		)
		(property "Value" ""
			(at 0 0 0)
			(layer "B.Fab")
			(effects
				(font
					(size 1.27 1.27)
				)
				(justify mirror)
			)
		)
		(duplicate_pad_numbers_are_jumpers no)
		(fp_line
			(start 0.7874 0.4064)
			(end 0.7874 -0.4064)
			(stroke
				(width 0.1524)
				(type default)
			)
			(layer "B.SilkS")
		)
		(fp_line
			(start 0.7874 -0.4064)
			(end -0.7874 -0.4064)
			(stroke
				(width 0.1524)
				(type default)
			)
			(layer "B.SilkS")
		)
		(fp_line
			(start -0.7874 0.4064)
			(end 0.7874 0.4064)
			(stroke
				(width 0.1524)
				(type default)
			)
			(layer "B.SilkS")
		)
		(fp_line
			(start -0.7874 -0.4064)
			(end -0.7874 0.4064)
			(stroke
				(width 0.1524)
				(type default)
			)
			(layer "B.SilkS")
		)
		(fp_line
			(start 0.67945 0.3048)
			(end 0.67945 -0.305054)
			(stroke
				(width 0.1)
				(type default)
			)
			(layer "B.Fab")
		)
		(fp_line
			(start 0.67945 -0.305054)
			(end 0.12065 -0.305054)
			(stroke
				(width 0.1)
				(type default)
			)
			(layer "B.Fab")
		)
		(fp_line
			(start 0.12065 0.3048)
			(end 0.67945 0.3048)
			(stroke
				(width 0.1)
				(type default)
			)
			(layer "B.Fab")
		)
		(fp_line
			(start 0.12065 0.2794)
			(end 0.12065 0.3048)
			(stroke
				(width 0.1)
				(type default)
			)
			(layer "B.Fab")
		)
		(fp_line
			(start 0.12065 -0.2794)
			(end -0.12065 -0.2794)
			(stroke
				(width 0.1)
				(type default)
			)
			(layer "B.Fab")
		)
		(fp_line
			(start 0.12065 -0.305054)
			(end 0.12065 -0.2794)
			(stroke
				(width 0.1)
				(type default)
			)
			(layer "B.Fab")
		)
		(fp_line
			(start -0.120396 0.3048)
			(end -0.120396 0.2794)
			(stroke
				(width 0.1)
				(type default)
			)
			(layer "B.Fab")
		)
		(fp_line
			(start -0.120396 0.2794)
			(end 0.12065 0.2794)
			(stroke
				(width 0.1)
				(type default)
			)
			(layer "B.Fab")
		)
		(fp_line
			(start -0.12065 -0.2794)
			(end -0.12065 -0.3048)
			(stroke
				(width 0.1)
				(type default)
			)
			(layer "B.Fab")
		)
		(fp_line
			(start -0.12065 -0.3048)
			(end -0.67945 -0.3048)
			(stroke
				(width 0.1)
				(type default)
			)
			(layer "B.Fab")
		)
		(fp_line
			(start -0.67945 0.3048)
			(end -0.120396 0.3048)
			(stroke
				(width 0.1)
				(type default)
			)
			(layer "B.Fab")
		)
		(fp_line
			(start -0.67945 -0.3048)
			(end -0.67945 0.3048)
			(stroke
				(width 0.1)
				(type default)
			)
			(layer "B.Fab")
		)
		(pad "1" smd circle
			(at 0.40005 0)
			(size 0 0)
			(layers "B.Cu" "B.Mask" "B.Paste")
			(net "NCSI_BMC_RXD0_R1")
		)
		(pad "2" smd circle
			(at -0.40005 0)
			(size 0 0)
			(layers "B.Cu" "B.Mask" "B.Paste")
			(net "RMII_OCP_BMC_RXD_0")
		)
	)
)
